# S9S_MB_2U (Grand Teton) — schematic netlist excerpt (pin names and nets, part order shuffled) for the footprints in the layout excerpt that follows; sources: Cadence DE-HDL packaged netlist, KiCad conversion of 03242023_DA0F0TMBIJ0_F0T_Motherboard_J_brd_V01_OCP.brd

C426  Q_CAP  22UF 4V 20% X6S  pkg C0402  page 77 : A = PVCCFA_EHV_FIVRA_CPU1 ; B = GND
R1434  Q_RES  10K 1% CHIP  pkg 0402LF  page 220 : A = FM_SYS_THROTTLE_R_N ; B = P3V3_AUX

(kicad_pcb
	(version 20260206)
	(generator "pcbnew")
	(generator_version "10.0")
	(general
		(thickness 1.6)
		(legacy_teardrops no)
	)
	(paper "A4")
	(title_block
		(title "03242023_DA0F0TMBIJ0_F0T_Motherboard_J_brd_V01_OCP.brd")
		(comment 1 "Grand Teton / footprints 980-981 of 6105")
	)
	(layers
		(0 "F.Cu" signal "TOP")
		(4 "In1.Cu" signal "GND")
		(6 "In2.Cu" signal "IN1")
		(8 "In3.Cu" signal "GND1")
		(10 "In4.Cu" signal "IN2")
		(12 "In5.Cu" signal "GND2")
		(14 "In6.Cu" signal "IN3")
		(16 "In7.Cu" signal "GND3")
		(18 "In8.Cu" signal "VCC")
		(20 "In9.Cu" signal "VCC1")
		(22 "In10.Cu" signal "GND4")
		(24 "In11.Cu" signal "IN4")
		(26 "In12.Cu" signal "GND5")
		(28 "In13.Cu" signal "IN5")
		(30 "In14.Cu" signal "GND6")
		(32 "In15.Cu" signal "IN6")
		(34 "In16.Cu" signal "GND7")
		(2 "B.Cu" signal "BOTTOM")
		(9 "F.Adhes" user "F.Adhesive")
		(11 "B.Adhes" user "B.Adhesive")
		(13 "F.Paste" user "Package Geometry/Pastemask Top")
		(15 "B.Paste" user "Package Geometry/Pastemask Bottom")
		(5 "F.SilkS" user "Ref Des/Silkscreen Top")
		(7 "B.SilkS" user "Ref Des/Silkscreen Bottom")
		(1 "F.Mask" user "Board Geometry/Soldermask Top")
		(3 "B.Mask" user "Board Geometry/Soldermask Bottom")
		(17 "Dwgs.User" user "User.Drawings")
		(19 "Cmts.User" user "User.Comments")
		(21 "Eco1.User" user "User.Eco1")
		(23 "Eco2.User" user "User.Eco2")
		(25 "Edge.Cuts" user "Board Geometry/Outline")
		(27 "Margin" user)
		(31 "F.CrtYd" user "Package Geometry/Place Bound Top")
		(29 "B.CrtYd" user "Package Geometry/Place Bound Bottom")
		(35 "F.Fab" user "Ref Des/Assembly Top")
		(33 "B.Fab" user "Ref Des/Assembly Bottom")
	)
	(footprint ""
		(layer "F.Cu")
		(at 193.38036 -119.344948)
		(property "Reference" "R1434"
			(at 0 0 0)
			(layer "F.SilkS")
			(hide yes)
			(effects
				(font
					(size 1.27 1.27)
				)
			)
		)
		(property "Value" ""
			(at 0 0 0)
			(layer "F.Fab")
			(effects
				(font
					(size 1.27 1.27)
				)
			)
		)
		(duplicate_pad_numbers_are_jumpers no)
		(fp_line
			(start -0.7874 -0.4064)
			(end 0.7874 -0.4064)
			(stroke
				(width 0.1524)
				(type default)
			)
			(layer "F.SilkS")
		)
		(fp_line
			(start -0.7874 0.4064)
			(end -0.7874 -0.4064)
			(stroke
				(width 0.1524)
				(type default)
			)
			(layer "F.SilkS")
		)
		(fp_line
			(start 0.7874 -0.4064)
			(end 0.7874 0.4064)
			(stroke
				(width 0.1524)
				(type default)
			)
			(layer "F.SilkS")
		)
		(fp_line
			(start 0.7874 0.4064)
			(end -0.7874 0.4064)
			(stroke
				(width 0.1524)
				(type default)
			)
			(layer "F.SilkS")
		)
		(fp_line
			(start -0.67945 -0.305054)
			(end -0.12065 -0.305054)
			(stroke
				(width 0.1)
				(type default)
			)
			(layer "F.Fab")
		)
		(fp_line
			(start -0.67945 0.3048)
			(end -0.67945 -0.305054)
			(stroke
				(width 0.1)
				(type default)
			)
			(layer "F.Fab")
		)
		(fp_line
			(start -0.12065 -0.305054)
			(end -0.12065 -0.2794)
			(stroke
				(width 0.1)
				(type default)
			)
			(layer "F.Fab")
		)
		(fp_line
			(start -0.12065 -0.2794)
			(end 0.12065 -0.2794)
			(stroke
				(width 0.1)
				(type default)
			)
			(layer "F.Fab")
		)
		(fp_line
			(start -0.12065 0.2794)
			(end -0.12065 0.3048)
			(stroke
				(width 0.1)
				(type default)
			)
			(layer "F.Fab")
		)
		(fp_line
			(start -0.12065 0.3048)
			(end -0.67945 0.3048)
			(stroke
				(width 0.1)
				(type default)
			)
			(layer "F.Fab")
		)
		(fp_line
			(start 0.120396 0.2794)
			(end -0.12065 0.2794)
			(stroke
				(width 0.1)
				(type default)
			)
			(layer "F.Fab")
		)
		(fp_line
			(start 0.120396 0.3048)
			(end 0.120396 0.2794)
			(stroke
				(width 0.1)
				(type default)
			)
			(layer "F.Fab")
		)
		(fp_line
			(start 0.12065 -0.3048)
			(end 0.67945 -0.3048)
			(stroke
				(width 0.1)
				(type default)
			)
			(layer "F.Fab")
		)
		(fp_line
			(start 0.12065 -0.2794)
			(end 0.12065 -0.3048)
			(stroke
				(width 0.1)
				(type default)
			)
			(layer "F.Fab")
		)
		(fp_line
			(start 0.67945 -0.3048)
			(end 0.67945 0.3048)
			(stroke
				(width 0.1)
				(type default)
			)
			(layer "F.Fab")
		)
		(fp_line
			(start 0.67945 0.3048)
			(end 0.120396 0.3048)
			(stroke
				(width 0.1)
				(type default)
			)
			(layer "F.Fab")
		)
		(pad "1" smd circle
			(at -0.40005 0)
			(size 0 0)
			(layers "F.Cu" "F.Mask" "F.Paste")
			(net "FM_SYS_THROTTLE_R_N")
		)
		(pad "2" smd circle
			(at 0.40005 0)
			(size 0 0)
			(layers "F.Cu" "F.Mask" "F.Paste")
			(net "P3V3_AUX")
		)
	)
	(footprint ""
		(layer "F.Cu")
		(at 118.542816 -240.277142 90)
		(property "Reference" "C426"
			(at 0 0 90)
			(layer "F.SilkS")
			(hide yes)
			(effects
				(font
					(size 1.27 1.27)
				)
			)
		)
		(property "Value" ""
			(at 0 0 90)
			(layer "F.Fab")
			(effects
				(font
					(size 1.27 1.27)
				)
			)
		)
		(duplicate_pad_numbers_are_jumpers no)
		(fp_line
			(start 0.7874 -0.4064)
			(end 0.7874 0.4064)
			(stroke
				(width 0.1524)
				(type default)
			)
			(layer "F.SilkS")
		)
		(fp_line
			(start -0.7874 -0.4064)
			(end 0.7874 -0.4064)
			(stroke
				(width 0.1524)
				(type default)
			)
			(layer "F.SilkS")
		)
		(fp_line
			(start 0.7874 0.4064)
			(end -0.7874 0.4064)
			(stroke
				(width 0.1524)
				(type default)
			)
			(layer "F.SilkS")
		)
		(fp_line
			(start -0.7874 0.4064)
			(end -0.7874 -0.4064)
			(stroke
				(width 0.1524)
				(type default)
			)
			(layer "F.SilkS")
		)
		(fp_line
			(start -0.12065 -0.305054)
			(end -0.12065 -0.2794)
			(stroke
				(width 0.1)
				(type default)
			)
			(layer "F.Fab")
		)
		(fp_line
			(start -0.67945 -0.305054)
			(end -0.12065 -0.305054)
			(stroke
				(width 0.1)
				(type default)
			)
			(layer "F.Fab")
		)
		(fp_line
			(start 0.67945 -0.3048)
			(end 0.67945 0.3048)
			(stroke
				(width 0.1)
				(type default)
			)
			(layer "F.Fab")
		)
		(fp_line
			(start 0.12065 -0.3048)
			(end 0.67945 -0.3048)
			(stroke
				(width 0.1)
				(type default)
			)
			(layer "F.Fab")
		)
		(fp_line
			(start 0.12065 -0.2794)
			(end 0.12065 -0.3048)
			(stroke
				(width 0.1)
				(type default)
			)
			(layer "F.Fab")
		)
		(fp_line
			(start -0.12065 -0.2794)
			(end 0.12065 -0.2794)
			(stroke
				(width 0.1)
				(type default)
			)
			(layer "F.Fab")
		)
		(fp_line
			(start 0.120396 0.2794)
			(end -0.12065 0.2794)
			(stroke
				(width 0.1)
				(type default)
			)
			(layer "F.Fab")
		)
		(fp_line
			(start -0.12065 0.2794)
			(end -0.12065 0.3048)
			(stroke
				(width 0.1)
				(type default)
			)
			(layer "F.Fab")
		)
		(fp_line
			(start 0.67945 0.3048)
			(end 0.120396 0.3048)
			(stroke
				(width 0.1)
				(type default)
			)
			(layer "F.Fab")
		)
		(fp_line
			(start 0.120396 0.3048)
			(end 0.120396 0.2794)
			(stroke
				(width 0.1)
				(type default)
			)
			(layer "F.Fab")
		)
		(fp_line
			(start -0.12065 0.3048)
			(end -0.67945 0.3048)
			(stroke
				(width 0.1)
				(type default)
			)
			(layer "F.Fab")
		)
		(fp_line
			(start -0.67945 0.3048)
			(end -0.67945 -0.305054)
			(stroke
				(width 0.1)
				(type default)
			)
			(layer "F.Fab")
		)
		(pad "1" smd circle
			(at -0.40005 0 90)
			(size 0 0)
			(layers "F.Cu" "F.Mask" "F.Paste")
			(net "PVCCFA_EHV_FIVRA_CPU1")
		)
		(pad "2" smd circle
			(at 0.40005 0 90)
			(size 0 0)
			(layers "F.Cu" "F.Mask" "F.Paste")
			(net "GND")
		)
	)
)
